(kicad_pcb
	(version 20260206)
	(generator "pcbnew")
	(generator_version "10.0")
	(general
		(thickness 1.21888)
		(legacy_teardrops no)
	)
	(paper "A4")
	(title_block
		(title "timecard-v9 — TimeCard-DC-V9_EXP.PcbDoc")
		(comment 1 "Time Appliance Project (Time Card) / footprints 312-322 of 402")
	)
	(layers
		(0 "F.Cu" signal "TOP")
		(4 "In1.Cu" signal "SGND")
		(6 "In2.Cu" signal "IN1")
		(8 "In3.Cu" signal "IN2")
		(10 "In4.Cu" signal "SGND1")
		(2 "B.Cu" signal "BOTTOM")
		(9 "F.Adhes" user "F.Adhesive")
		(11 "B.Adhes" user "B.Adhesive")
		(13 "F.Paste" user "Top Paste")
		(15 "B.Paste" user "Bottom Paste")
		(5 "F.SilkS" user "Top Overlay")
		(7 "B.SilkS" user "Bottom Overlay")
		(1 "F.Mask" user "Top Solder")
		(3 "B.Mask" user "Bottom Solder")
		(17 "Dwgs.User" user "User.Drawings")
		(19 "Cmts.User" user "User.Comments")
		(21 "Eco1.User" user "User.Eco1")
		(23 "Eco2.User" user "User.Eco2")
		(25 "Edge.Cuts" user)
		(27 "Margin" user)
		(31 "F.CrtYd" user "Top Courtyard")
		(29 "B.CrtYd" user "Bottom Courtyard")
		(35 "F.Fab" user "Top Component Center")
		(33 "B.Fab" user "Bottom Component Center")
	)
	(footprint "Vault:RESC1005X40X25NL10T10"
		(layer "B.Cu")
		(at 207.95084 120.1412 180)
		(property "Reference" "R135"
			(at 2.63244 -0.001921 0)
			(unlocked yes)
			(layer "B.SilkS")
			(effects
				(font
					(size 0.762 0.762)
					(thickness 0.2032)
				)
				(justify mirror)
			)
		)
		(property "Value" "4.7K_1%_0402"
			(at -2.732271 -8.747465 90)
			(unlocked yes)
			(layer "B.SilkS")
			(hide yes)
			(effects
				(font
					(size 0.762 0.762)
					(thickness 0.2032)
				)
				(justify mirror)
			)
		)
		(sheetname "10-M2_GPS")
		(sheetfile "10-M2_GPS.kicad_sch")
		(duplicate_pad_numbers_are_jumpers no)
		(pad "1" smd rect
			(at -0.425 0 90)
			(size 0.6 0.65)
			(layers "B.Cu" "B.Mask" "B.Paste")
			(net "GPS2_PIN13")
		)
		(pad "2" smd rect
			(at 0.425 0 90)
			(size 0.6 0.65)
			(layers "B.Cu" "B.Mask" "B.Paste")
			(net "GNSS2_P3V3")
		)
	)
	(footprint "Capacitors:CAPC1005X06N"
		(layer "B.Cu")
		(at 141.5756 151.7886 90)
		(property "Reference" "C53"
			(at 2.41349 0.046545 270)
			(unlocked yes)
			(layer "B.SilkS")
			(effects
				(font
					(size 0.762 0.762)
					(thickness 0.2286)
				)
				(justify left bottom mirror)
			)
		)
		(property "Value" "CAP_0402_0.1UF_50V"
			(at -3.382645 0.2921 0)
			(unlocked yes)
			(layer "B.SilkS")
			(hide yes)
			(effects
				(font
					(size 0.762 0.762)
					(thickness 0.2286)
				)
				(justify left bottom mirror)
			)
		)
		(sheetname "04-PCIe_JTAG")
		(sheetfile "04-PCIe_JTAG.kicad_sch")
		(duplicate_pad_numbers_are_jumpers no)
		(pad "1" smd rect
			(at -0.43 0)
			(size 0.64 0.68)
			(layers "B.Cu" "B.Mask" "B.Paste")
			(net "NetC53_1")
		)
		(pad "2" smd rect
			(at 0.43 0)
			(size 0.64 0.68)
			(layers "B.Cu" "B.Mask" "B.Paste")
			(net "PCIE_TX3_N")
		)
	)
	(footprint "Vault:FP-0402-L_1_0_1-W_0_5_0_1-IPC_C"
		(layer "B.Cu")
		(at 213.58331 126.42791 180)
		(property "Reference" "C113"
			(at -0.29229 -1.461359 180)
			(unlocked yes)
			(layer "B.SilkS")
			(effects
				(font
					(size 0.762 0.762)
					(thickness 0.254)
				)
				(justify mirror)
			)
		)
		(property "Value" "0.1uF_25V_0402"
			(at -2.465551 -9.864615 90)
			(unlocked yes)
			(layer "B.SilkS")
			(hide yes)
			(effects
				(font
					(size 0.762 0.762)
					(thickness 0.254)
				)
				(justify mirror)
			)
		)
		(sheetname "09-USBUart_PPSMUX_UARTMUX")
		(sheetfile "09-USBUart_PPSMUX_UARTMUX.kicad_sch")
		(duplicate_pad_numbers_are_jumpers no)
		(fp_line
			(start 0.65607 0.7)
			(end -0.65606 0.7)
			(stroke
				(width 0.2)
				(type solid)
			)
			(layer "B.SilkS")
		)
		(fp_line
			(start 0.65607 -0.7)
			(end -0.65606 -0.7)
			(stroke
				(width 0.2)
				(type solid)
			)
			(layer "B.SilkS")
		)
		(fp_line
			(start 0.75607 0.4)
			(end -0.75606 0.4)
			(stroke
				(width 0.2)
				(type solid)
			)
			(layer "B.CrtYd")
		)
		(fp_line
			(start 0.75607 -0.4)
			(end 0.75607 0.4)
			(stroke
				(width 0.2)
				(type solid)
			)
			(layer "B.CrtYd")
		)
		(fp_line
			(start 0.75607 -0.4)
			(end -0.75606 -0.4)
			(stroke
				(width 0.2)
				(type solid)
			)
			(layer "B.CrtYd")
		)
		(fp_line
			(start -0.75606 -0.4)
			(end -0.75606 0.4)
			(stroke
				(width 0.2)
				(type solid)
			)
			(layer "B.CrtYd")
		)
		(fp_line
			(start 0.75607 0.4)
			(end -0.75606 0.4)
			(stroke
				(width 0.2)
				(type solid)
			)
			(layer "B.Fab")
		)
		(fp_line
			(start 0.75607 -0.4)
			(end 0.75607 0.4)
			(stroke
				(width 0.2)
				(type solid)
			)
			(layer "B.Fab")
		)
		(fp_line
			(start 0.75607 -0.4)
			(end -0.75606 -0.4)
			(stroke
				(width 0.2)
				(type solid)
			)
			(layer "B.Fab")
		)
		(fp_line
			(start 0.5 0)
			(end -0.5 0)
			(stroke
				(width 0.1)
				(type solid)
			)
			(layer "B.Fab")
		)
		(fp_line
			(start 0 -0.5)
			(end 0 0.5)
			(stroke
				(width 0.1)
				(type solid)
			)
			(layer "B.Fab")
		)
		(fp_line
			(start -0.75606 -0.4)
			(end -0.75606 0.4)
			(stroke
				(width 0.2)
				(type solid)
			)
			(layer "B.Fab")
		)
		(fp_text user "${REFERENCE}"
			(at -0.00001 -0.09602 360)
			(unlocked yes)
			(layer "B.Fab")
			(effects
				(font
					(face "Arial")
					(size 0.63 0.63)
					(thickness 0.1)
				)
				(justify left bottom mirror)
			)
		)
		(pad "1" smd rect
			(at -0.36553 0 180)
			(size 0.58106 0.51213)
			(layers "B.Cu" "B.Mask" "B.Paste")
			(net "GNSS2_P5V0")
			(solder_mask_margin 0)
			(solder_paste_margin 0)
		)
		(pad "2" smd rect
			(at 0.36554 0 180)
			(size 0.58106 0.51213)
			(layers "B.Cu" "B.Mask" "B.Paste")
			(net "GND")
			(solder_mask_margin 0)
			(solder_paste_margin 0)
		)
	)
	(footprint "Vault:FP-0402-L_1_0_1-W_0_5_0_1-IPC_C"
		(layer "B.Cu")
		(at 154.8216 116.0162 180)
		(property "Reference" "C69"
			(at 0.2286 1.573069 0)
			(unlocked yes)
			(layer "B.SilkS")
			(effects
				(font
					(size 0.762 0.762)
					(thickness 0.2286)
				)
				(justify mirror)
			)
		)
		(property "Value" "0.1uF_25V_0402"
			(at -2.744951 -8.290305 90)
			(unlocked yes)
			(layer "B.SilkS")
			(hide yes)
			(effects
				(font
					(size 0.762 0.762)
					(thickness 0.2286)
				)
				(justify mirror)
			)
		)
		(sheetname "08-DIPSwitches_I2C")
		(sheetfile "08-DIPSwitches_I2C.kicad_sch")
		(duplicate_pad_numbers_are_jumpers no)
		(fp_line
			(start 0.65607 0.7)
			(end -0.65607 0.7)
			(stroke
				(width 0.2)
				(type solid)
			)
			(layer "B.SilkS")
		)
		(fp_line
			(start 0.65607 -0.7)
			(end -0.65607 -0.7)
			(stroke
				(width 0.2)
				(type solid)
			)
			(layer "B.SilkS")
		)
		(fp_line
			(start 0.75607 0.4)
			(end -0.75607 0.4)
			(stroke
				(width 0.2)
				(type solid)
			)
			(layer "B.CrtYd")
		)
		(fp_line
			(start 0.75607 -0.4)
			(end 0.75607 0.4)
			(stroke
				(width 0.2)
				(type solid)
			)
			(layer "B.CrtYd")
		)
		(fp_line
			(start 0.75607 -0.4)
			(end -0.75607 -0.4)
			(stroke
				(width 0.2)
				(type solid)
			)
			(layer "B.CrtYd")
		)
		(fp_line
			(start -0.75607 -0.4)
			(end -0.75607 0.4)
			(stroke
				(width 0.2)
				(type solid)
			)
			(layer "B.CrtYd")
		)
		(fp_line
			(start 0.75607 0.4)
			(end -0.75607 0.4)
			(stroke
				(width 0.2)
				(type solid)
			)
			(layer "B.Fab")
		)
		(fp_line
			(start 0.75607 -0.4)
			(end 0.75607 0.4)
			(stroke
				(width 0.2)
				(type solid)
			)
			(layer "B.Fab")
		)
		(fp_line
			(start 0.75607 -0.4)
			(end -0.75607 -0.4)
			(stroke
				(width 0.2)
				(type solid)
			)
			(layer "B.Fab")
		)
		(fp_line
			(start 0.5 0)
			(end -0.5 0)
			(stroke
				(width 0.1)
				(type solid)
			)
			(layer "B.Fab")
		)
		(fp_line
			(start 0 -0.5)
			(end 0 0.5)
			(stroke
				(width 0.1)
				(type solid)
			)
			(layer "B.Fab")
		)
		(fp_line
			(start -0.75607 -0.4)
			(end -0.75607 0.4)
			(stroke
				(width 0.2)
				(type solid)
			)
			(layer "B.Fab")
		)
		(fp_text user "${REFERENCE}"
			(at -0.00001 -0.09602 360)
			(unlocked yes)
			(layer "B.Fab")
			(effects
				(font
					(face "Arial")
					(size 0.63 0.63)
					(thickness 0.1)
				)
				(justify left bottom mirror)
			)
		)
		(pad "1" smd rect
			(at -0.36554 0 180)
			(size 0.58106 0.51213)
			(layers "B.Cu" "B.Mask" "B.Paste")
			(net "+3.3V")
			(solder_mask_margin 0)
			(solder_paste_margin 0)
		)
		(pad "2" smd rect
			(at 0.36554 0 180)
			(size 0.58106 0.51213)
			(layers "B.Cu" "B.Mask" "B.Paste")
			(net "GND")
			(solder_mask_margin 0)
			(solder_paste_margin 0)
		)
	)
	(footprint "Vault:FP-0603-L_1_6_0_2-W_0_8_0-MFG"
		(layer "B.Cu")
		(at 88.5116 69.33347 90)
		(property "Reference" "C22"
			(at -0.98273 1.316655 270)
			(unlocked yes)
			(layer "B.SilkS")
			(effects
				(font
					(size 0.762 0.762)
					(thickness 0.2286)
				)
				(justify left bottom mirror)
			)
		)
		(property "Value" "10uF_16V_0603"
			(at 1.606965 -21.7043 0)
			(unlocked yes)
			(layer "B.SilkS")
			(hide yes)
			(effects
				(font
					(size 0.762 0.762)
					(thickness 0.2286)
				)
				(justify left bottom mirror)
			)
		)
		(sheetname "03-POWER")
		(sheetfile "03-POWER.kicad_sch")
		(duplicate_pad_numbers_are_jumpers no)
		(fp_line
			(start -0.9 -0.825)
			(end 0.9 -0.825)
			(stroke
				(width 0.2)
				(type solid)
			)
			(layer "B.SilkS")
		)
		(fp_line
			(start -0.9 0.825)
			(end 0.9 0.825)
			(stroke
				(width 0.2)
				(type solid)
			)
			(layer "B.SilkS")
		)
		(fp_line
			(start 1.15 -0.6)
			(end 1.15 0.6)
			(stroke
				(width 0.2)
				(type solid)
			)
			(layer "B.CrtYd")
		)
		(fp_line
			(start -1.15 -0.6)
			(end 1.15 -0.6)
			(stroke
				(width 0.2)
				(type solid)
			)
			(layer "B.CrtYd")
		)
		(fp_line
			(start -1.15 -0.6)
			(end -1.15 0.6)
			(stroke
				(width 0.2)
				(type solid)
			)
			(layer "B.CrtYd")
		)
		(fp_line
			(start -1.15 0.6)
			(end 1.15 0.6)
			(stroke
				(width 0.2)
				(type solid)
			)
			(layer "B.CrtYd")
		)
		(fp_line
			(start 1.15 -0.6)
			(end 1.15 0.6)
			(stroke
				(width 0.2)
				(type solid)
			)
			(layer "B.Fab")
		)
		(fp_line
			(start -1.15 -0.6)
			(end 1.15 -0.6)
			(stroke
				(width 0.2)
				(type solid)
			)
			(layer "B.Fab")
		)
		(fp_line
			(start -1.15 -0.6)
			(end -1.15 0.6)
			(stroke
				(width 0.2)
				(type solid)
			)
			(layer "B.Fab")
		)
		(fp_line
			(start 0 -0.5)
			(end 0 0.5)
			(stroke
				(width 0.1)
				(type solid)
			)
			(layer "B.Fab")
		)
		(fp_line
			(start -0.49999 0)
			(end 0.5 0)
			(stroke
				(width 0.1)
				(type solid)
			)
			(layer "B.Fab")
		)
		(fp_line
			(start -1.15 0.6)
			(end 1.15 0.6)
			(stroke
				(width 0.2)
				(type solid)
			)
			(layer "B.Fab")
		)
		(fp_text user "${REFERENCE}"
			(at -0.00001 -0.09601 270)
			(unlocked yes)
			(layer "B.Fab")
			(effects
				(font
					(face "Arial")
					(size 0.63 0.63)
					(thickness 0.1)
				)
				(justify left bottom mirror)
			)
		)
		(pad "1" smd rect
			(at -0.7 0 90)
			(size 0.7 0.7)
			(layers "B.Cu" "B.Mask" "B.Paste")
			(net "+3.3V")
			(solder_mask_margin 0)
			(solder_paste_margin 0)
		)
		(pad "2" smd rect
			(at 0.70001 0 90)
			(size 0.7 0.7)
			(layers "B.Cu" "B.Mask" "B.Paste")
			(net "GND")
			(solder_mask_margin 0)
			(solder_paste_margin 0)
		)
	)
	(footprint "Vault:FP-MK212BG-MFG"
		(layer "B.Cu")
		(at 103.1216 64.3162 180)
		(property "Reference" "C60"
			(at -1 0.906655 0)
			(unlocked yes)
			(layer "B.SilkS")
			(effects
				(font
					(size 0.762 0.762)
					(thickness 0.2286)
				)
				(justify left bottom mirror)
			)
		)
		(property "Value" "10uF"
			(at -1.5875 -3.433445 0)
			(unlocked yes)
			(layer "B.SilkS")
			(hide yes)
			(effects
				(font
					(size 0.762 0.762)
					(thickness 0.2286)
				)
				(justify left bottom mirror)
			)
		)
		(sheetname "05-GPS_IMU_SENSORS")
		(sheetfile "05-GPS_IMU_SENSORS.kicad_sch")
		(duplicate_pad_numbers_are_jumpers no)
		(fp_line
			(start 0.125 0.725)
			(end -0.125 0.725)
			(stroke
				(width 0.2)
				(type solid)
			)
			(layer "B.SilkS")
		)
		(fp_line
			(start 0.125 -0.725)
			(end -0.125 -0.725)
			(stroke
				(width 0.2)
				(type solid)
			)
			(layer "B.SilkS")
		)
		(fp_line
			(start 1.6 0.825)
			(end -1.6 0.825)
			(stroke
				(width 0.2)
				(type solid)
			)
			(layer "B.CrtYd")
		)
		(fp_line
			(start 1.6 -0.825)
			(end 1.6 0.825)
			(stroke
				(width 0.2)
				(type solid)
			)
			(layer "B.CrtYd")
		)
		(fp_line
			(start 1.6 -0.825)
			(end -1.6 -0.825)
			(stroke
				(width 0.2)
				(type solid)
			)
			(layer "B.CrtYd")
		)
		(fp_line
			(start -1.6 -0.825)
			(end -1.6 0.825)
			(stroke
				(width 0.2)
				(type solid)
			)
			(layer "B.CrtYd")
		)
		(fp_line
			(start 1.6 0.825)
			(end -1.6 0.825)
			(stroke
				(width 0.2)
				(type solid)
			)
			(layer "B.Fab")
		)
		(fp_line
			(start 1.6 -0.825)
			(end 1.6 0.825)
			(stroke
				(width 0.2)
				(type solid)
			)
			(layer "B.Fab")
		)
		(fp_line
			(start 1.6 -0.825)
			(end -1.6 -0.825)
			(stroke
				(width 0.2)
				(type solid)
			)
			(layer "B.Fab")
		)
		(fp_line
			(start 0.5 0)
			(end -0.5 0)
			(stroke
				(width 0.1)
				(type solid)
			)
			(layer "B.Fab")
		)
		(fp_line
			(start 0 -0.5)
			(end 0 0.5)
			(stroke
				(width 0.1)
				(type solid)
			)
			(layer "B.Fab")
		)
		(fp_line
			(start -1.6 -0.825)
			(end -1.6 0.825)
			(stroke
				(width 0.2)
				(type solid)
			)
			(layer "B.Fab")
		)
		(fp_text user "${REFERENCE}"
			(at -0.00001 -0.09601 360)
			(unlocked yes)
			(layer "B.Fab")
			(effects
				(font
					(face "Arial")
					(size 0.63 0.63)
					(thickness 0.1)
				)
				(justify left bottom mirror)
			)
		)
		(pad "1" smd rect
			(at -1 0 180)
			(size 1 1.25)
			(layers "B.Cu" "B.Mask" "B.Paste")
			(net "+5.0V")
			(solder_mask_margin 0)
			(solder_paste_margin 0)
		)
		(pad "2" smd rect
			(at 1 0 180)
			(size 1 1.25)
			(layers "B.Cu" "B.Mask" "B.Paste")
			(net "GND")
			(solder_mask_margin 0)
			(solder_paste_margin 0)
		)
	)
	(footprint "Capacitors:CAPC1005X06N"
		(layer "B.Cu")
		(at 132.5586 151.7886 90)
		(property "Reference" "C48"
			(at 2.41349 -0.867855 270)
			(unlocked yes)
			(layer "B.SilkS")
			(effects
				(font
					(size 0.762 0.762)
					(thickness 0.2286)
				)
				(justify left bottom mirror)
			)
		)
		(property "Value" "CAP_0402_0.1UF_50V"
			(at -3.382645 0.2921 0)
			(unlocked yes)
			(layer "B.SilkS")
			(hide yes)
			(effects
				(font
					(size 0.762 0.762)
					(thickness 0.2286)
				)
				(justify left bottom mirror)
			)
		)
		(sheetname "04-PCIe_JTAG")
		(sheetfile "04-PCIe_JTAG.kicad_sch")
		(duplicate_pad_numbers_are_jumpers no)
		(pad "1" smd rect
			(at -0.43 0)
			(size 0.64 0.68)
			(layers "B.Cu" "B.Mask" "B.Paste")
			(net "NetC48_1")
		)
		(pad "2" smd rect
			(at 0.43 0)
			(size 0.64 0.68)
			(layers "B.Cu" "B.Mask" "B.Paste")
			(net "PCIE_TX1_P")
		)
	)
	(footprint "Vault:CAPC1608X87X45ML20T05"
		(layer "B.Cu")
		(at 207.5216 141.2162 180)
		(property "Reference" "C37"
			(at -0.1286 -1.273069 180)
			(unlocked yes)
			(layer "B.SilkS")
			(effects
				(font
					(size 0.762 0.762)
					(thickness 0.2286)
				)
				(justify mirror)
			)
		)
		(property "Value" "0.1uF"
			(at 2.069035 -2.630671 0)
			(unlocked yes)
			(layer "B.SilkS")
			(hide yes)
			(effects
				(font
					(size 0.762 0.762)
					(thickness 0.2286)
				)
				(justify mirror)
			)
		)
		(sheetname "05-GPS_IMU_SENSORS")
		(sheetfile "05-GPS_IMU_SENSORS.kicad_sch")
		(duplicate_pad_numbers_are_jumpers no)
		(pad "1" smd rect
			(at -0.7 0 90)
			(size 1.1 1.05)
			(layers "B.Cu" "B.Mask" "B.Paste")
			(net "GND")
		)
		(pad "2" smd rect
			(at 0.7 0 90)
			(size 1.1 1.05)
			(layers "B.Cu" "B.Mask" "B.Paste")
			(net "GNSS2_P5V0")
		)
	)
	(footprint "Vault:RESC1005X40X25ML05T05"
		(layer "B.Cu")
		(at 209.8216 126.2162 90)
		(property "Reference" "R181"
			(at 0.22626 0.873069 270)
			(unlocked yes)
			(layer "B.SilkS")
			(effects
				(font
					(size 0.762 0.762)
					(thickness 0.254)
				)
				(justify mirror)
			)
		)
		(property "Value" "10K_5%_0402"
			(at -2.884671 -8.061875 0)
			(unlocked yes)
			(layer "B.SilkS")
			(hide yes)
			(effects
				(font
					(size 0.762 0.762)
					(thickness 0.254)
				)
				(justify mirror)
			)
		)
		(sheetname "09-USBUart_PPSMUX_UARTMUX")
		(sheetfile "09-USBUart_PPSMUX_UARTMUX.kicad_sch")
		(duplicate_pad_numbers_are_jumpers no)
		(pad "1" smd rect
			(at -0.5 0)
			(size 0.65 0.65)
			(layers "B.Cu" "B.Mask" "B.Paste")
			(net "GND")
		)
		(pad "2" smd rect
			(at 0.5 0)
			(size 0.65 0.65)
			(layers "B.Cu" "B.Mask" "B.Paste")
			(net "NetR49_1")
		)
	)
	(footprint "Capacitors:CAPC1005X06N"
		(layer "B.Cu")
		(at 125.5736 151.7886 90)
		(property "Reference" "C45"
			(at 2.835 -0.445345 270)
			(unlocked yes)
			(layer "B.SilkS")
			(effects
				(font
					(size 0.762 0.762)
					(thickness 0.2286)
				)
				(justify left bottom mirror)
			)
		)
		(property "Value" "CAP_0402_0.1UF_50V"
			(at -3.382645 0.2921 0)
			(unlocked yes)
			(layer "B.SilkS")
			(hide yes)
			(effects
				(font
					(size 0.762 0.762)
					(thickness 0.2286)
				)
				(justify left bottom mirror)
			)
		)
		(sheetname "04-PCIe_JTAG")
		(sheetfile "04-PCIe_JTAG.kicad_sch")
		(duplicate_pad_numbers_are_jumpers no)
		(pad "1" smd rect
			(at -0.43 0)
			(size 0.64 0.68)
			(layers "B.Cu" "B.Mask" "B.Paste")
			(net "NetC45_1")
		)
		(pad "2" smd rect
			(at 0.43 0)
			(size 0.64 0.68)
			(layers "B.Cu" "B.Mask" "B.Paste")
			(net "PCIE_CLK_N")
		)
	)
	(footprint "Vault:RESC1005X40X25NL10T10"
		(layer "B.Cu")
		(at 183.19649 92.2162 -90)
		(property "Reference" "R184"
			(at 2.396998 -2.70424 180)
			(unlocked yes)
			(layer "B.SilkS")
			(effects
				(font
					(size 1.524 1.524)
					(thickness 0.254)
				)
				(justify mirror)
			)
		)
		(property "Value" "10K_1%_0402"
			(at -2.759202 -8.036515 180)
			(unlocked yes)
			(layer "B.SilkS")
			(hide yes)
			(effects
				(font
					(size 1.524 1.524)
					(thickness 0.254)
				)
				(justify mirror)
			)
		)
		(sheetname "03-POWER")
		(sheetfile "03-POWER.kicad_sch")
		(duplicate_pad_numbers_are_jumpers no)
		(pad "1" smd rect
			(at -0.425 0 180)
			(size 0.6 0.65)
			(layers "B.Cu" "B.Mask" "B.Paste")
			(net "GND")
		)
		(pad "2" smd rect
			(at 0.425 0 180)
			(size 0.6 0.65)
			(layers "B.Cu" "B.Mask" "B.Paste")
			(net "NetR183_2")
		)
	)
)
